# BASEBOARD_FAB2 (Tioga Pass) — schematic netlist excerpt (pin names and nets, part order shuffled) for the footprints in the layout excerpt that follows; sources: Cadence DE-HDL packaged netlist, KiCad conversion of Wiwynn_Tioga_Pass_MB.brd

C4D2  CAPP  270UF 16V 20% OSCON  pkg 2626  page 204 : A = VR_FET_SW_P12V_STBY_PVCCIN_CPU0 ; B = GND
C8F12  CAP  0.22UF 16V 10% X7R  pkg 0402  page 185 : A = P3E_PCH_TX_0_DN ; B = P3E_PCH_M2_SATA6G_TX_R_DN

(kicad_pcb
	(version 20260206)
	(generator "pcbnew")
	(generator_version "10.0")
	(general
		(thickness 1.6)
		(legacy_teardrops no)
	)
	(paper "A4")
	(title_block
		(title "Wiwynn_Tioga_Pass_MB.brd")
		(comment 1 "Tioga Pass / footprints 415-416 of 4770")
	)
	(layers
		(0 "F.Cu" signal "TOP")
		(4 "In1.Cu" signal "L2GND")
		(6 "In2.Cu" signal "L3")
		(8 "In3.Cu" signal "L4GND")
		(10 "In4.Cu" signal "L5")
		(12 "In5.Cu" signal "L6GND")
		(14 "In6.Cu" signal "L7VCC")
		(16 "In7.Cu" signal "L8VCC")
		(18 "In8.Cu" signal "L9GND")
		(20 "In9.Cu" signal "L10")
		(22 "In10.Cu" signal "L11GND")
		(24 "In11.Cu" signal "L12")
		(26 "In12.Cu" signal "L13GND")
		(2 "B.Cu" signal "BOTTOM")
		(9 "F.Adhes" user "F.Adhesive")
		(11 "B.Adhes" user "B.Adhesive")
		(13 "F.Paste" user "Package Geometry/Pastemask Top")
		(15 "B.Paste" user "Package Geometry/Pastemask Bottom")
		(5 "F.SilkS" user "Ref Des/Silkscreen Top")
		(7 "B.SilkS" user "Ref Des/Silkscreen Bottom")
		(1 "F.Mask" user "Board Geometry/Soldermask Top")
		(3 "B.Mask" user "Board Geometry/Soldermask Bottom")
		(17 "Dwgs.User" user "User.Drawings")
		(19 "Cmts.User" user "User.Comments")
		(21 "Eco1.User" user "User.Eco1")
		(23 "Eco2.User" user "User.Eco2")
		(25 "Edge.Cuts" user "Board Geometry/Outline")
		(27 "Margin" user)
		(31 "F.CrtYd" user "Package Geometry/Place Bound Top")
		(29 "B.CrtYd" user "Package Geometry/Place Bound Bottom")
		(35 "F.Fab" user "Ref Des/Assembly Top")
		(33 "B.Fab" user "Ref Des/Assembly Bottom")
	)
	(footprint ""
		(layer "F.Cu")
		(at 380.032768 -32.3215 -90)
		(property "Reference" "C8F12"
			(at 0 0 270)
			(layer "F.SilkS")
			(hide yes)
			(effects
				(font
					(size 1.27 1.27)
				)
			)
		)
		(property "Value" ""
			(at 0 0 270)
			(layer "F.Fab")
			(effects
				(font
					(size 1.27 1.27)
				)
			)
		)
		(duplicate_pad_numbers_are_jumpers no)
		(fp_poly
			(pts
				(xy 0.3048 -0.1016) (xy 0.3048 0.9906) (xy -0.3048 0.9906) (xy -0.3048 -0.1016)
			)
			(stroke
				(width 0)
				(type default)
			)
			(fill no)
			(layer "F.CrtYd")
		)
		(fp_line
			(start -0.3048 0.9906)
			(end 0.3048 0.9906)
			(stroke
				(width 0.1)
				(type default)
			)
			(layer "F.Fab")
		)
		(fp_line
			(start 0.3048 0.9906)
			(end 0.3048 -0.1016)
			(stroke
				(width 0.1)
				(type default)
			)
			(layer "F.Fab")
		)
		(fp_line
			(start -0.3048 -0.1016)
			(end -0.3048 0.9906)
			(stroke
				(width 0.1)
				(type default)
			)
			(layer "F.Fab")
		)
		(fp_line
			(start 0.3048 -0.1016)
			(end -0.3048 -0.1016)
			(stroke
				(width 0.1)
				(type default)
			)
			(layer "F.Fab")
		)
		(pad "1" smd rect
			(at 0 0 270)
			(size 0.508 0.508)
			(layers "F.Cu" "F.Mask" "F.Paste")
			(net "P3E_PCH_TX_0_DN")
		)
		(pad "2" smd rect
			(at 0 0.889 270)
			(size 0.508 0.508)
			(layers "F.Cu" "F.Mask" "F.Paste")
			(net "P3E_PCH_M2_SATA6G_TX_R_DN")
		)
		(zone
			(layer "F.Cu")
			(hatch none 0.5)
			(connect_pads
				(clearance 0)
			)
			(min_thickness 0.25)
			(keepout
				(tracks not_allowed)
				(vias allowed)
				(pads allowed)
				(copperpour not_allowed)
				(footprints allowed)
			)
			(placement
				(enabled no)
				(sheetname "")
			)
			(fill
				(thermal_gap 0.5)
				(thermal_bridge_width 0.5)
				(island_removal_mode 0)
			)
			(polygon
				(pts
					(xy 379.397768 -32.5755) (xy 379.397768 -32.0675) (xy 379.778768 -32.0675) (xy 379.778768 -32.5755)
				)
			)
		)
		(zone
			(layer "F.Cu")
			(hatch none 0.5)
			(connect_pads
				(clearance 0)
			)
			(min_thickness 0.25)
			(keepout
				(tracks allowed)
				(vias not_allowed)
				(pads allowed)
				(copperpour not_allowed)
				(footprints allowed)
			)
			(placement
				(enabled no)
				(sheetname "")
			)
			(fill
				(thermal_gap 0.5)
				(thermal_bridge_width 0.5)
				(island_removal_mode 0)
			)
			(polygon
				(pts
					(xy 379.778768 -32.5755) (xy 379.778768 -32.0675) (xy 379.397768 -32.0675) (xy 379.397768 -32.5755)
				)
			)
		)
	)
	(footprint ""
		(layer "F.Cu")
		(at 190.754 -86.741 -90)
		(property "Reference" "C4D2"
			(at -0.762 7.72033 90)
			(unlocked yes)
			(layer "F.SilkS")
			(effects
				(font
					(size 0.7874 0.5842)
					(thickness 0.1524)
				)
				(justify left)
			)
		)
		(property "Value" ""
			(at 0 0 270)
			(layer "F.Fab")
			(effects
				(font
					(size 1.27 1.27)
				)
			)
		)
		(duplicate_pad_numbers_are_jumpers no)
		(fp_line
			(start -3.400044 6.067044)
			(end -0.9017 6.067044)
			(stroke
				(width 0.1524)
				(type default)
			)
			(layer "F.SilkS")
		)
		(fp_line
			(start 0.9017 6.067044)
			(end 3.400044 6.067044)
			(stroke
				(width 0.1524)
				(type default)
			)
			(layer "F.SilkS")
		)
		(fp_line
			(start 3.400044 6.067044)
			(end 3.400044 0.028956)
			(stroke
				(width 0.1524)
				(type default)
			)
			(layer "F.SilkS")
		)
		(fp_line
			(start -0.9017 1.587754)
			(end -0.7239 1.587754)
			(stroke
				(width 0.1524)
				(type default)
			)
			(layer "F.SilkS")
		)
		(fp_line
			(start 0.7239 1.587754)
			(end 0.9017 1.587754)
			(stroke
				(width 0.1524)
				(type default)
			)
			(layer "F.SilkS")
		)
		(fp_line
			(start 0.9017 1.587754)
			(end 0.9017 -1.714246)
			(stroke
				(width 0.1524)
				(type default)
			)
			(layer "F.SilkS")
		)
		(fp_line
			(start -3.400044 0.028956)
			(end -3.400044 6.067044)
			(stroke
				(width 0.1524)
				(type default)
			)
			(layer "F.SilkS")
		)
		(fp_line
			(start 3.400044 0.028956)
			(end 2.638044 -0.733044)
			(stroke
				(width 0.1524)
				(type default)
			)
			(layer "F.SilkS")
		)
		(fp_line
			(start -2.638044 -0.733044)
			(end -3.400044 0.028956)
			(stroke
				(width 0.1524)
				(type default)
			)
			(layer "F.SilkS")
		)
		(fp_line
			(start -0.9017 -0.733044)
			(end -2.638044 -0.733044)
			(stroke
				(width 0.1524)
				(type default)
			)
			(layer "F.SilkS")
		)
		(fp_line
			(start 2.638044 -0.733044)
			(end 0.9017 -0.733044)
			(stroke
				(width 0.1524)
				(type default)
			)
			(layer "F.SilkS")
		)
		(fp_line
			(start -0.9017 -1.714246)
			(end -0.9017 1.587754)
			(stroke
				(width 0.1524)
				(type default)
			)
			(layer "F.SilkS")
		)
		(fp_line
			(start -0.7239 -1.714246)
			(end -0.9017 -1.714246)
			(stroke
				(width 0.1524)
				(type default)
			)
			(layer "F.SilkS")
		)
		(fp_line
			(start 0.9017 -1.714246)
			(end 0.7239 -1.714246)
			(stroke
				(width 0.1524)
				(type default)
			)
			(layer "F.SilkS")
		)
		(fp_poly
			(pts
				(xy -3.400044 6.067044) (xy 3.400044 6.067044) (xy 3.400044 0.028956) (xy 2.638044 -0.733044) (xy -2.638044 -0.733044)
				(xy -3.400044 0.028956)
			)
			(stroke
				(width 0)
				(type default)
			)
			(fill no)
			(layer "F.CrtYd")
		)
		(fp_line
			(start -3.400044 6.067044)
			(end 3.400044 6.067044)
			(stroke
				(width 0.1)
				(type default)
			)
			(layer "F.Fab")
		)
		(fp_line
			(start 3.400044 6.067044)
			(end 3.400044 0.028956)
			(stroke
				(width 0.1)
				(type default)
			)
			(layer "F.Fab")
		)
		(fp_line
			(start -3.400044 0.028956)
			(end -3.400044 6.067044)
			(stroke
				(width 0.1)
				(type default)
			)
			(layer "F.Fab")
		)
		(fp_line
			(start 3.400044 0.028956)
			(end 2.638044 -0.733044)
			(stroke
				(width 0.1)
				(type default)
			)
			(layer "F.Fab")
		)
		(fp_line
			(start -2.638044 -0.733044)
			(end -3.400044 0.028956)
			(stroke
				(width 0.1)
				(type default)
			)
			(layer "F.Fab")
		)
		(fp_line
			(start 2.638044 -0.733044)
			(end -2.638044 -0.733044)
			(stroke
				(width 0.1)
				(type default)
			)
			(layer "F.Fab")
		)
		(fp_circle
			(center 0 2.667)
			(end 0 -0.733044)
			(stroke
				(width 0.1)
				(type default)
			)
			(fill no)
			(layer "F.Fab")
		)
		(pad "1" smd rect
			(at 0 0 270)
			(size 0.7874 3.429)
			(layers "F.Cu" "F.Mask" "F.Paste")
			(net "VR_FET_SW_P12V_STBY_PVCCIN_CPU0")
		)
		(pad "2" smd rect
			(at 0 5.334 270)
			(size 0.7874 3.429)
			(layers "F.Cu" "F.Mask" "F.Paste")
			(net "GND")
		)
	)
)
